# T6G (Grand Teton) — schematic netlist excerpt (pin names and nets, part order shuffled) for the footprints in the layout excerpt that follows; sources: Cadence DE-HDL packaged netlist, KiCad conversion of 04192023_DAF0TMB3IC0_F0TG_MB_C_brd_V02_OCP.brd

Q71  MOSFET_NCH_DUAL  PJT138K IC  pkg SOT363XD  page 127
  S1  = GND
  G1  = FM_SWB_PWRGD
  D2  = FM_SWB_PWRGD_ISO
  S2  = GND
  G2  = FM_SWB_PWRGD_N
  D1  = FM_SWB_PWRGD_N

R680  Q_RES  49.9 1% CHIP  pkg 0201LF  page 298 : A = SMB_RT_CPU0_P2_ROM_MUX_1D_SCL ; B = SMB_RT_CPU0_P2_ROM_MUX_1D_R_SCL
C2120  Q_CAP  22UF 4V 20% X6S  pkg C0402  page 74 : A = PVDD11_S3_P1 ; B = GND

(kicad_pcb
	(version 20260206)
	(generator "pcbnew")
	(generator_version "10.0")
	(general
		(thickness 1.6)
		(legacy_teardrops no)
	)
	(paper "A4")
	(title_block
		(title "04192023_DAF0TMB3IC0_F0TG_MB_C_brd_V02_OCP.brd")
		(comment 1 "Grand Teton / footprints 8000-8002 of 8354")
	)
	(layers
		(0 "F.Cu" signal "TOP")
		(4 "In1.Cu" signal "GND")
		(6 "In2.Cu" signal "IN1")
		(8 "In3.Cu" signal "GND1")
		(10 "In4.Cu" signal "IN2")
		(12 "In5.Cu" signal "GND2")
		(14 "In6.Cu" signal "IN3")
		(16 "In7.Cu" signal "GND3")
		(18 "In8.Cu" signal "VCC")
		(20 "In9.Cu" signal "VCC1")
		(22 "In10.Cu" signal "GND4")
		(24 "In11.Cu" signal "IN4")
		(26 "In12.Cu" signal "GND5")
		(28 "In13.Cu" signal "IN5")
		(30 "In14.Cu" signal "GND6")
		(32 "In15.Cu" signal "IN6")
		(34 "In16.Cu" signal "GND7")
		(2 "B.Cu" signal "BOTTOM")
		(9 "F.Adhes" user "F.Adhesive")
		(11 "B.Adhes" user "B.Adhesive")
		(13 "F.Paste" user "Package Geometry/Pastemask Top")
		(15 "B.Paste" user "Package Geometry/Pastemask Bottom")
		(5 "F.SilkS" user "Ref Des/Silkscreen Top")
		(7 "B.SilkS" user "Ref Des/Silkscreen Bottom")
		(1 "F.Mask" user "Board Geometry/Soldermask Top")
		(3 "B.Mask" user "Board Geometry/Soldermask Bottom")
		(17 "Dwgs.User" user "User.Drawings")
		(19 "Cmts.User" user "User.Comments")
		(21 "Eco1.User" user "User.Eco1")
		(23 "Eco2.User" user "User.Eco2")
		(25 "Edge.Cuts" user "Board Geometry/Outline")
		(27 "Margin" user)
		(31 "F.CrtYd" user "Package Geometry/Place Bound Top")
		(29 "B.CrtYd" user "Package Geometry/Place Bound Bottom")
		(35 "F.Fab" user "Ref Des/Assembly Top")
		(33 "B.Fab" user "Ref Des/Assembly Bottom")
	)
	(footprint ""
		(layer "B.Cu")
		(at 125.135386 -264.354564)
		(property "Reference" "C2120"
			(at 0 0 0)
			(layer "B.SilkS")
			(hide yes)
			(effects
				(font
					(size 1.27 1.27)
				)
				(justify mirror)
			)
		)
		(property "Value" ""
			(at 0 0 0)
			(layer "B.Fab")
			(effects
				(font
					(size 1.27 1.27)
				)
				(justify mirror)
			)
		)
		(duplicate_pad_numbers_are_jumpers no)
		(fp_line
			(start -0.7874 -0.4064)
			(end -0.7874 0.4064)
			(stroke
				(width 0.1524)
				(type default)
			)
			(layer "B.SilkS")
		)
		(fp_line
			(start -0.7874 0.4064)
			(end 0.7874 0.4064)
			(stroke
				(width 0.1524)
				(type default)
			)
			(layer "B.SilkS")
		)
		(fp_line
			(start 0.7874 -0.4064)
			(end -0.7874 -0.4064)
			(stroke
				(width 0.1524)
				(type default)
			)
			(layer "B.SilkS")
		)
		(fp_line
			(start 0.7874 0.4064)
			(end 0.7874 -0.4064)
			(stroke
				(width 0.1524)
				(type default)
			)
			(layer "B.SilkS")
		)
		(fp_line
			(start -0.67945 -0.3048)
			(end -0.67945 0.3048)
			(stroke
				(width 0.1)
				(type default)
			)
			(layer "B.Fab")
		)
		(fp_line
			(start -0.67945 0.3048)
			(end -0.120396 0.3048)
			(stroke
				(width 0.1)
				(type default)
			)
			(layer "B.Fab")
		)
		(fp_line
			(start -0.12065 -0.3048)
			(end -0.67945 -0.3048)
			(stroke
				(width 0.1)
				(type default)
			)
			(layer "B.Fab")
		)
		(fp_line
			(start -0.12065 -0.2794)
			(end -0.12065 -0.3048)
			(stroke
				(width 0.1)
				(type default)
			)
			(layer "B.Fab")
		)
		(fp_line
			(start -0.120396 0.2794)
			(end 0.12065 0.2794)
			(stroke
				(width 0.1)
				(type default)
			)
			(layer "B.Fab")
		)
		(fp_line
			(start -0.120396 0.3048)
			(end -0.120396 0.2794)
			(stroke
				(width 0.1)
				(type default)
			)
			(layer "B.Fab")
		)
		(fp_line
			(start 0.12065 -0.305054)
			(end 0.12065 -0.2794)
			(stroke
				(width 0.1)
				(type default)
			)
			(layer "B.Fab")
		)
		(fp_line
			(start 0.12065 -0.2794)
			(end -0.12065 -0.2794)
			(stroke
				(width 0.1)
				(type default)
			)
			(layer "B.Fab")
		)
		(fp_line
			(start 0.12065 0.2794)
			(end 0.12065 0.3048)
			(stroke
				(width 0.1)
				(type default)
			)
			(layer "B.Fab")
		)
		(fp_line
			(start 0.12065 0.3048)
			(end 0.67945 0.3048)
			(stroke
				(width 0.1)
				(type default)
			)
			(layer "B.Fab")
		)
		(fp_line
			(start 0.67945 -0.305054)
			(end 0.12065 -0.305054)
			(stroke
				(width 0.1)
				(type default)
			)
			(layer "B.Fab")
		)
		(fp_line
			(start 0.67945 0.3048)
			(end 0.67945 -0.305054)
			(stroke
				(width 0.1)
				(type default)
			)
			(layer "B.Fab")
		)
		(pad "1" smd circle
			(at 0.40005 0 180)
			(size 0 0)
			(layers "B.Cu" "B.Mask" "B.Paste")
			(net "PVDD11_S3_P1")
		)
		(pad "2" smd circle
			(at -0.40005 0 180)
			(size 0 0)
			(layers "B.Cu" "B.Mask" "B.Paste")
			(net "GND")
		)
	)
	(footprint ""
		(layer "B.Cu")
		(at 420.968424 -420.534592)
		(property "Reference" "R680"
			(at 0 0 0)
			(layer "B.SilkS")
			(hide yes)
			(effects
				(font
					(size 1.27 1.27)
				)
				(justify mirror)
			)
		)
		(property "Value" ""
			(at 0 0 0)
			(layer "B.Fab")
			(effects
				(font
					(size 1.27 1.27)
				)
				(justify mirror)
			)
		)
		(duplicate_pad_numbers_are_jumpers no)
		(fp_line
			(start -0.32512 -0.175006)
			(end -0.32512 0.175006)
			(stroke
				(width 0.1)
				(type default)
			)
			(layer "B.Fab")
		)
		(fp_line
			(start -0.32512 0.175006)
			(end 0.32512 0.175006)
			(stroke
				(width 0.1)
				(type default)
			)
			(layer "B.Fab")
		)
		(fp_line
			(start 0.32512 -0.175006)
			(end -0.32512 -0.175006)
			(stroke
				(width 0.1)
				(type default)
			)
			(layer "B.Fab")
		)
		(fp_line
			(start 0.32512 0.175006)
			(end 0.32512 -0.175006)
			(stroke
				(width 0.1)
				(type default)
			)
			(layer "B.Fab")
		)
		(pad "1" smd rect
			(at 0.2667 0 180)
			(size 0.3048 0.381)
			(layers "B.Cu" "B.Mask" "B.Paste")
			(net "SMB_RT_CPU0_P2_ROM_MUX_1D_SCL")
		)
		(pad "2" smd rect
			(at -0.2667 0)
			(size 0.3048 0.381)
			(layers "B.Cu" "B.Mask" "B.Paste")
			(net "SMB_RT_CPU0_P2_ROM_MUX_1D_R_SCL")
		)
	)
	(footprint ""
		(layer "B.Cu")
		(at 355.26599 -417.63696)
		(property "Reference" "Q71"
			(at -1.36906 -2.460244 0)
			(unlocked yes)
			(layer "B.SilkS")
			(effects
				(font
					(size 0.7874 0.5842)
					(thickness 0.1524)
				)
				(justify left mirror)
			)
		)
		(property "Value" ""
			(at 0 0 0)
			(layer "B.Fab")
			(effects
				(font
					(size 1.27 1.27)
				)
				(justify mirror)
			)
		)
		(duplicate_pad_numbers_are_jumpers no)
		(fp_line
			(start -1.332738 -1.100074)
			(end -1.332738 1.100074)
			(stroke
				(width 0.1524)
				(type default)
			)
			(layer "B.SilkS")
		)
		(fp_line
			(start -1.332738 1.100074)
			(end 1.332738 1.100074)
			(stroke
				(width 0.1524)
				(type default)
			)
			(layer "B.SilkS")
		)
		(fp_line
			(start -0.4826 -1.100074)
			(end -1.332738 -1.100074)
			(stroke
				(width 0.1524)
				(type default)
			)
			(layer "B.SilkS")
		)
		(fp_line
			(start 0 -0.541274)
			(end -0.4826 -1.100074)
			(stroke
				(width 0.1524)
				(type default)
			)
			(layer "B.SilkS")
		)
		(fp_line
			(start 0.4826 -1.100074)
			(end 0 -0.541274)
			(stroke
				(width 0.1524)
				(type default)
			)
			(layer "B.SilkS")
		)
		(fp_line
			(start 1.332738 -1.100074)
			(end 0.4826 -1.100074)
			(stroke
				(width 0.1524)
				(type default)
			)
			(layer "B.SilkS")
		)
		(fp_line
			(start 1.332738 1.100074)
			(end 1.332738 -1.100074)
			(stroke
				(width 0.1524)
				(type default)
			)
			(layer "B.SilkS")
		)
		(fp_poly
			(pts
				(xy 0.939038 -1.628648) (xy 1.290066 -2.33045) (xy 0.58801 -2.33045)
			)
			(stroke
				(width 0)
				(type default)
			)
			(fill yes)
			(layer "B.SilkS")
		)
		(fp_line
			(start -0.674878 -1.100074)
			(end -0.674878 1.100074)
			(stroke
				(width 0.1)
				(type default)
			)
			(layer "B.Fab")
		)
		(fp_line
			(start -0.674878 1.100074)
			(end 0.674878 1.100074)
			(stroke
				(width 0.1)
				(type default)
			)
			(layer "B.Fab")
		)
		(fp_line
			(start 0.674878 -1.100074)
			(end -0.674878 -1.100074)
			(stroke
				(width 0.1)
				(type default)
			)
			(layer "B.Fab")
		)
		(fp_line
			(start 0.674878 1.100074)
			(end 0.674878 -1.100074)
			(stroke
				(width 0.1)
				(type default)
			)
			(layer "B.Fab")
		)
		(fp_poly
			(pts
				(xy 2.2352 -0.298958) (xy 2.2352 -1.001014) (xy 1.533144 -0.649986)
			)
			(stroke
				(width 0)
				(type default)
			)
			(fill yes)
			(layer "B.Fab")
		)
		(pad "1" smd rect
			(at 0.94996 -0.649986 90)
			(size 0.4318 0.508)
			(layers "B.Cu" "B.Mask" "B.Paste")
			(net "GND")
		)
		(pad "2" smd rect
			(at 0.94996 0 90)
			(size 0.4318 0.508)
			(layers "B.Cu" "B.Mask" "B.Paste")
			(net "FM_SWB_PWRGD")
		)
		(pad "3" smd rect
			(at 0.94996 0.649986 90)
			(size 0.4318 0.508)
			(layers "B.Cu" "B.Mask" "B.Paste")
			(net "FM_SWB_PWRGD_ISO")
		)
		(pad "4" smd rect
			(at -0.94996 0.649986 90)
			(size 0.4318 0.508)
			(layers "B.Cu" "B.Mask" "B.Paste")
			(net "GND")
		)
		(pad "5" smd rect
			(at -0.94996 0 90)
			(size 0.4318 0.508)
			(layers "B.Cu" "B.Mask" "B.Paste")
			(net "FM_SWB_PWRGD_N")
		)
		(pad "6" smd rect
			(at -0.94996 -0.649986 90)
			(size 0.4318 0.508)
			(layers "B.Cu" "B.Mask" "B.Paste")
			(net "FM_SWB_PWRGD_N")
		)
	)
)
